(kicad_pcb
	(version 20260206)
	(generator "pcbnew")
	(generator_version "10.0")
	(general
		(thickness 1.6)
		(legacy_teardrops no)
	)
	(paper "A4")
	(title_block
		(title "Bryce Canyon_F.DPB_16315-1-OCP.brd")
		(comment 1 "Bryce Canyon / footprints 1892-1895 of 2223")
	)
	(layers
		(0 "F.Cu" signal "TOP")
		(4 "In1.Cu" signal "L2GND")
		(6 "In2.Cu" signal "L3")
		(8 "In3.Cu" signal "L4GND")
		(10 "In4.Cu" signal "L5")
		(12 "In5.Cu" signal "L6VCC")
		(14 "In6.Cu" signal "L7VCC")
		(16 "In7.Cu" signal "L8")
		(18 "In8.Cu" signal "L9GND")
		(20 "In9.Cu" signal "L10")
		(22 "In10.Cu" signal "L11GND")
		(2 "B.Cu" signal "BOTTOM")
		(9 "F.Adhes" user "F.Adhesive")
		(11 "B.Adhes" user "B.Adhesive")
		(13 "F.Paste" user "Package Geometry/Pastemask Top")
		(15 "B.Paste" user "Package Geometry/Pastemask Bottom")
		(5 "F.SilkS" user "Ref Des/Silkscreen Top")
		(7 "B.SilkS" user "Ref Des/Silkscreen Bottom")
		(1 "F.Mask" user "Board Geometry/Soldermask Top")
		(3 "B.Mask" user "Board Geometry/Soldermask Bottom")
		(17 "Dwgs.User" user "User.Drawings")
		(19 "Cmts.User" user "User.Comments")
		(21 "Eco1.User" user "User.Eco1")
		(23 "Eco2.User" user "User.Eco2")
		(25 "Edge.Cuts" user "Board Geometry/Outline")
		(27 "Margin" user)
		(31 "F.CrtYd" user "Package Geometry/Place Bound Top")
		(29 "B.CrtYd" user "Package Geometry/Place Bound Bottom")
		(35 "F.Fab" user "Ref Des/Assembly Top")
		(33 "B.Fab" user "Ref Des/Assembly Bottom")
	)
	(footprint ""
		(layer "F.Cu")
		(at 185.950098 -172.909992 -90)
		(property "Reference" "HDDSAS17"
			(at 0 0 270)
			(layer "F.SilkS")
			(hide yes)
			(effects
				(font
					(size 1.27 1.27)
				)
			)
		)
		(property "Value" "SKT-SAS15P-14P-45-GP"
			(at -20.7645 -8.9789 270)
			(unlocked yes)
			(layer "F.Fab")
			(hide yes)
			(effects
				(font
					(size 1.016 1.016)
					(thickness 0.1524)
				)
			)
		)
		(property "Device Type" "10120818-001C-TRLF"
			(at -20.7645 -10.5029 270)
			(unlocked yes)
			(layer "F.Fab")
			(hide yes)
			(effects
				(font
					(size 1.016 1.016)
					(thickness 0.1524)
				)
			)
		)
		(duplicate_pad_numbers_are_jumpers no)
		(fp_line
			(start 1.651 4.2926)
			(end 1.651 3.0099)
			(stroke
				(width 0.1524)
				(type default)
			)
			(layer "F.SilkS")
		)
		(fp_line
			(start 8.509 4.2926)
			(end 1.651 4.2926)
			(stroke
				(width 0.1524)
				(type default)
			)
			(layer "F.SilkS")
		)
		(fp_line
			(start -23.4188 3.0099)
			(end -23.4188 -3.2512)
			(stroke
				(width 0.1524)
				(type default)
			)
			(layer "F.SilkS")
		)
		(fp_line
			(start 1.651 3.0099)
			(end -23.4188 3.0099)
			(stroke
				(width 0.1524)
				(type default)
			)
			(layer "F.SilkS")
		)
		(fp_line
			(start 8.509 3.0099)
			(end 8.509 4.2926)
			(stroke
				(width 0.1524)
				(type default)
			)
			(layer "F.SilkS")
		)
		(fp_line
			(start 23.4188 3.0099)
			(end 8.509 3.0099)
			(stroke
				(width 0.1524)
				(type default)
			)
			(layer "F.SilkS")
		)
		(fp_line
			(start -23.4188 -3.2512)
			(end 23.4188 -3.2512)
			(stroke
				(width 0.1524)
				(type default)
			)
			(layer "F.SilkS")
		)
		(fp_line
			(start 23.4188 -3.2512)
			(end 23.4188 3.0099)
			(stroke
				(width 0.1524)
				(type default)
			)
			(layer "F.SilkS")
		)
		(fp_line
			(start 15.5067 -3.3401)
			(end 16.2687 -3.3401)
			(stroke
				(width 0.3302)
				(type default)
			)
			(layer "F.SilkS")
		)
		(fp_poly
			(pts
				(xy 15.868904 -3.230372) (xy 16.503904 -3.865372) (xy 15.233904 -3.865372)
			)
			(stroke
				(width 0)
				(type default)
			)
			(fill yes)
			(layer "F.SilkS")
		)
		(fp_poly
			(pts
				(xy -22.8727 -2.7559) (xy 22.8727 -2.7559) (xy 22.8727 2.7559) (xy 8.255 2.7559) (xy 8.255 3.5179)
				(xy 1.905 3.5179) (xy 1.905 2.7559) (xy -22.8727 2.7559)
			)
			(stroke
				(width 0)
				(type default)
			)
			(fill no)
			(layer "F.CrtYd")
		)
		(fp_poly
			(pts
				(xy 1.397 4.5466) (xy 1.397 3.2639) (xy -23.6728 3.2639) (xy -23.6728 -3.5052) (xy 23.6728 -3.5052)
				(xy 23.6728 -0.00635) (xy 22.8727 -0.00635) (xy 22.8727 -2.7559) (xy -22.8727 -2.7559) (xy -22.8727 2.7559)
				(xy 1.905 2.7559) (xy 1.905 3.5179) (xy 8.255 3.5179) (xy 8.255 2.7559) (xy 22.8727 2.7559) (xy 22.8727 0.00635)
				(xy 23.6728 0.00635) (xy 23.6728 3.2639) (xy 8.763 3.2639) (xy 8.763 4.5466)
			)
			(stroke
				(width 0)
				(type default)
			)
			(fill no)
			(layer "F.CrtYd")
		)
		(fp_poly
			(pts
				(xy 1.397 4.5466) (xy 1.397 3.2639) (xy -23.6728 3.2639) (xy -23.6728 -3.5052) (xy 23.6728 -3.5052)
				(xy 23.6728 3.2639) (xy 8.763 3.2639) (xy 8.763 4.5466)
			)
			(stroke
				(width 0)
				(type default)
			)
			(fill no)
			(layer "F.Fab")
		)
		(pad "" np_thru_hole circle
			(at -18.874994 0 270)
			(size 0.254 0.254)
			(drill 1.3462)
			(layers "*.Cu" "*.Mask")
			(clearance 0.9017)
			(thermal_gap 0.9017)
		)
		(pad "" np_thru_hole circle
			(at 18.874994 0 270)
			(size 0.254 0.254)
			(drill 0.9398)
			(layers "*.Cu" "*.Mask")
			(clearance 0.6985)
			(thermal_gap 0.6985)
		)
		(pad "G1" smd rect
			(at 21.874988 0 270)
			(size 2.5908 2.5908)
			(layers "F.Cu" "F.Mask" "F.Paste")
			(net "GND")
		)
		(pad "G2" smd rect
			(at -21.874988 0 270)
			(size 2.5908 2.5908)
			(layers "F.Cu" "F.Mask" "F.Paste")
			(net "GND")
		)
		(pad "P1" smd rect
			(at 1.905 -1.82499 270)
			(size 0.6096 2.3622)
			(layers "F.Cu" "F.Mask" "F.Paste")
			(net "Net_2131")
		)
		(pad "P2" smd rect
			(at 0.635 -1.82499 270)
			(size 0.6096 2.3622)
			(layers "F.Cu" "F.Mask" "F.Paste")
			(net "Net_2132")
		)
		(pad "P3" smd rect
			(at -0.635 -1.82499 270)
			(size 0.6096 2.3622)
			(layers "F.Cu" "F.Mask" "F.Paste")
			(net "Net_2133")
		)
		(pad "P4" smd rect
			(at -1.905 -1.82499 270)
			(size 0.6096 2.3622)
			(layers "F.Cu" "F.Mask" "F.Paste")
			(net "GND")
		)
		(pad "P5" smd rect
			(at -3.175 -1.82499 270)
			(size 0.6096 2.3622)
			(layers "F.Cu" "F.Mask" "F.Paste")
			(net "HDD_PRSNT_17")
		)
		(pad "P6" smd rect
			(at -4.445 -1.82499 270)
			(size 0.6096 2.3622)
			(layers "F.Cu" "F.Mask" "F.Paste")
			(net "GND")
		)
		(pad "P7" smd rect
			(at -5.715 -1.82499 270)
			(size 0.6096 2.3622)
			(layers "F.Cu" "F.Mask" "F.Paste")
			(net "5V_PRE_17")
		)
		(pad "P8" smd rect
			(at -6.985 -1.82499 270)
			(size 0.6096 2.3622)
			(layers "F.Cu" "F.Mask" "F.Paste")
			(net "P5V_HDD17")
		)
		(pad "P9" smd rect
			(at -8.255 -1.82499 270)
			(size 0.6096 2.3622)
			(layers "F.Cu" "F.Mask" "F.Paste")
			(net "P5V_HDD17")
		)
		(pad "P10" smd rect
			(at -9.525 -1.82499 270)
			(size 0.6096 2.3622)
			(layers "F.Cu" "F.Mask" "F.Paste")
			(net "GND")
		)
		(pad "P11" smd rect
			(at -10.795 -1.82499 270)
			(size 0.6096 2.3622)
			(layers "F.Cu" "F.Mask" "F.Paste")
			(net "ACT_HDD_17")
		)
		(pad "P12" smd rect
			(at -12.065 -1.82499 270)
			(size 0.6096 2.3622)
			(layers "F.Cu" "F.Mask" "F.Paste")
			(net "GND")
		)
		(pad "P13" smd rect
			(at -13.335 -1.82499 270)
			(size 0.6096 2.3622)
			(layers "F.Cu" "F.Mask" "F.Paste")
			(net "12V_PRE_17")
		)
		(pad "P14" smd rect
			(at -14.605 -1.82499 270)
			(size 0.6096 2.3622)
			(layers "F.Cu" "F.Mask" "F.Paste")
			(net "P12V_HDD17")
		)
		(pad "P15" smd rect
			(at -15.875 -1.82499 270)
			(size 0.6096 2.3622)
			(layers "F.Cu" "F.Mask" "F.Paste")
			(net "P12V_HDD17")
		)
		(pad "S1" smd rect
			(at 15.875 -1.82499 270)
			(size 0.6096 2.3622)
			(layers "F.Cu" "F.Mask" "F.Paste")
			(net "GND")
		)
		(pad "S2" smd rect
			(at 14.605 -1.82499 270)
			(size 0.6096 2.3622)
			(layers "F.Cu" "F.Mask" "F.Paste")
			(net "SAS_HDD_RX_P17")
		)
		(pad "S3" smd rect
			(at 13.335 -1.82499 270)
			(size 0.6096 2.3622)
			(layers "F.Cu" "F.Mask" "F.Paste")
			(net "SAS_HDD_RX_N17")
		)
		(pad "S4" smd rect
			(at 12.065 -1.82499 270)
			(size 0.6096 2.3622)
			(layers "F.Cu" "F.Mask" "F.Paste")
			(net "GND")
		)
		(pad "S5" smd rect
			(at 10.795 -1.82499 270)
			(size 0.6096 2.3622)
			(layers "F.Cu" "F.Mask" "F.Paste")
			(net "PHY_DRV_A_TO_SCC_A_17_DN")
		)
		(pad "S6" smd rect
			(at 9.525 -1.82499 270)
			(size 0.6096 2.3622)
			(layers "F.Cu" "F.Mask" "F.Paste")
			(net "PHY_DRV_A_TO_SCC_A_17_DP")
		)
		(pad "S7" smd rect
			(at 8.255 -1.82499 270)
			(size 0.6096 2.3622)
			(layers "F.Cu" "F.Mask" "F.Paste")
			(net "GND")
		)
		(pad "S8" smd rect
			(at 7.480046 2.845054 270)
			(size 0.508 2.3622)
			(layers "F.Cu" "F.Mask" "F.Paste")
			(net "GND")
		)
		(pad "S9" smd rect
			(at 6.679946 2.845054 270)
			(size 0.508 2.3622)
			(layers "F.Cu" "F.Mask" "F.Paste")
			(net "Net_454")
		)
		(pad "S10" smd rect
			(at 5.8801 2.845054 270)
			(size 0.508 2.3622)
			(layers "F.Cu" "F.Mask" "F.Paste")
			(net "Net_346")
		)
		(pad "S11" smd rect
			(at 5.08 2.845054 270)
			(size 0.508 2.3622)
			(layers "F.Cu" "F.Mask" "F.Paste")
			(net "GND")
		)
		(pad "S12" smd rect
			(at 4.2799 2.845054 270)
			(size 0.508 2.3622)
			(layers "F.Cu" "F.Mask" "F.Paste")
			(net "Net_382")
		)
		(pad "S13" smd rect
			(at 3.480054 2.845054 270)
			(size 0.508 2.3622)
			(layers "F.Cu" "F.Mask" "F.Paste")
			(net "Net_418")
		)
		(pad "S14" smd rect
			(at 2.679954 2.845054 270)
			(size 0.508 2.3622)
			(layers "F.Cu" "F.Mask" "F.Paste")
			(net "GND")
		)
		(zone
			(layer "F.Cu")
			(hatch none 0.5)
			(connect_pads
				(clearance 0)
			)
			(min_thickness 0.25)
			(keepout
				(tracks not_allowed)
				(vias allowed)
				(pads allowed)
				(copperpour not_allowed)
				(footprints allowed)
			)
			(placement
				(enabled no)
				(sheetname "")
			)
			(fill
				(thermal_gap 0.5)
				(thermal_bridge_width 0.5)
				(island_removal_mode 0)
			)
			(polygon
				(pts
					(xy 189.607698 -189.648592) (xy 182.533798 -189.648592) (xy 182.533798 -196.582792) (xy 183.638698 -196.582792)
					(xy 183.638698 -192.467992) (xy 188.261498 -192.467992) (xy 188.261498 -196.582792) (xy 189.607698 -196.582792)
				)
			)
		)
		(zone
			(layer "F.Cu")
			(hatch none 0.5)
			(connect_pads
				(clearance 0)
			)
			(min_thickness 0.25)
			(keepout
				(tracks allowed)
				(vias not_allowed)
				(pads allowed)
				(copperpour not_allowed)
				(footprints allowed)
			)
			(placement
				(enabled no)
				(sheetname "")
			)
			(fill
				(thermal_gap 0.5)
				(thermal_bridge_width 0.5)
				(island_removal_mode 0)
			)
			(polygon
				(pts
					(xy 189.607698 -189.648592) (xy 182.533798 -189.648592) (xy 182.533798 -196.582792) (xy 183.638698 -196.582792)
					(xy 183.638698 -192.467992) (xy 188.261498 -192.467992) (xy 188.261498 -196.582792) (xy 189.607698 -196.582792)
				)
			)
		)
		(zone
			(layer "F.Cu")
			(hatch none 0.5)
			(connect_pads
				(clearance 0)
			)
			(min_thickness 0.25)
			(keepout
				(tracks allowed)
				(vias not_allowed)
				(pads allowed)
				(copperpour not_allowed)
				(footprints allowed)
			)
			(placement
				(enabled no)
				(sheetname "")
			)
			(fill
				(thermal_gap 0.5)
				(thermal_bridge_width 0.5)
				(island_removal_mode 0)
			)
			(polygon
				(pts
					(xy 189.607698 -156.171392) (xy 182.533798 -156.171392) (xy 182.533798 -149.237192) (xy 183.638698 -149.237192)
					(xy 183.638698 -153.351992) (xy 188.261498 -153.351992) (xy 188.261498 -149.237192) (xy 189.607698 -149.237192)
				)
			)
		)
		(zone
			(layer "F.Cu")
			(hatch none 0.5)
			(connect_pads
				(clearance 0)
			)
			(min_thickness 0.25)
			(keepout
				(tracks not_allowed)
				(vias allowed)
				(pads allowed)
				(copperpour not_allowed)
				(footprints allowed)
			)
			(placement
				(enabled no)
				(sheetname "")
			)
			(fill
				(thermal_gap 0.5)
				(thermal_bridge_width 0.5)
				(island_removal_mode 0)
			)
			(polygon
				(pts
					(xy 189.607698 -156.171392) (xy 182.533798 -156.171392) (xy 182.533798 -149.237192) (xy 183.638698 -149.237192)
					(xy 183.638698 -153.351992) (xy 188.261498 -153.351992) (xy 188.261498 -149.237192) (xy 189.607698 -149.237192)
				)
			)
		)
		(zone
			(layers "F.Cu" "B.Cu" "In1.Cu" "In2.Cu" "In3.Cu" "In4.Cu" "In5.Cu" "In6.Cu"
				"In7.Cu" "In8.Cu" "In9.Cu" "In10.Cu"
			)
			(hatch none 0.5)
			(connect_pads
				(clearance 0)
			)
			(min_thickness 0.25)
			(keepout
				(tracks not_allowed)
				(vias allowed)
				(pads allowed)
				(copperpour not_allowed)
				(footprints allowed)
			)
			(placement
				(enabled no)
				(sheetname "")
			)
			(fill
				(thermal_gap 0.5)
				(thermal_bridge_width 0.5)
				(island_removal_mode 0)
			)
			(polygon
				(pts
					(arc
						(start 186.724798 -154.034998)
						(mid 185.175398 -154.034998)
						(end 186.724798 -154.034998)
					)
				)
			)
		)
		(zone
			(layers "F.Cu" "B.Cu" "In1.Cu" "In2.Cu" "In3.Cu" "In4.Cu" "In5.Cu" "In6.Cu"
				"In7.Cu" "In8.Cu" "In9.Cu" "In10.Cu"
			)
			(hatch none 0.5)
			(connect_pads
				(clearance 0)
			)
			(min_thickness 0.25)
			(keepout
				(tracks not_allowed)
				(vias allowed)
				(pads allowed)
				(copperpour not_allowed)
				(footprints allowed)
			)
			(placement
				(enabled no)
				(sheetname "")
			)
			(fill
				(thermal_gap 0.5)
				(thermal_bridge_width 0.5)
				(island_removal_mode 0)
			)
			(polygon
				(pts
					(arc
						(start 186.927998 -191.784986)
						(mid 184.972198 -191.784986)
						(end 186.927998 -191.784986)
					)
				)
			)
		)
	)
	(footprint ""
		(layer "F.Cu")
		(at 450.815202 -259.01015)
		(property "Reference" "R1243"
			(at 0 0 0)
			(layer "F.SilkS")
			(hide yes)
			(effects
				(font
					(size 1.27 1.27)
				)
			)
		)
		(property "Value" "49K9R2F-L-GP"
			(at 0.064008 -3.993896 0)
			(unlocked yes)
			(layer "F.Fab")
			(hide yes)
			(effects
				(font
					(size 1.016 1.016)
					(thickness 0.1524)
				)
			)
		)
		(property "Device Type" "R402H16"
			(at 0.064008 -5.517896 0)
			(unlocked yes)
			(layer "F.Fab")
			(hide yes)
			(effects
				(font
					(size 1.016 1.016)
					(thickness 0.1524)
				)
			)
		)
		(duplicate_pad_numbers_are_jumpers no)
		(fp_line
			(start -0.508 -0.9398)
			(end -0.508 0.9398)
			(stroke
				(width 0.1524)
				(type default)
			)
			(layer "F.SilkS")
		)
		(fp_line
			(start 0.508 -0.9398)
			(end -0.508 -0.9398)
			(stroke
				(width 0.1524)
				(type default)
			)
			(layer "F.SilkS")
		)
		(fp_rect
			(start -0.508 0.9398)
			(end 0.508 -0.9398)
			(stroke
				(width 0)
				(type default)
			)
			(fill no)
			(layer "F.CrtYd")
		)
		(fp_rect
			(start -0.508 0.9398)
			(end 0.508 -0.9398)
			(stroke
				(width 0)
				(type default)
			)
			(fill no)
			(layer "F.Fab")
		)
		(pad "1" smd custom
			(at 0 -0.4445)
			(size 0.1397 0.1397)
			(layers "F.Cu" "F.Mask" "F.Paste")
			(net "P12V_A")
			(options
				(clearance outline)
				(anchor circle)
			)
			(primitives
				(gr_poly
					(pts
						(arc
							(start -0.1778 -0.2794)
							(mid -0.249642 -0.249642)
							(end -0.2794 -0.1778)
						)
						(arc
							(start -0.2794 0.1778)
							(mid -0.249642 0.249642)
							(end -0.1778 0.2794)
						)
						(arc
							(start 0.1778 0.2794)
							(mid 0.249642 0.249642)
							(end 0.2794 0.1778)
						)
						(arc
							(start 0.2794 -0.1778)
							(mid 0.249642 -0.249642)
							(end 0.1778 -0.2794)
						)
					)
					(width 0)
					(fill yes)
				)
			)
		)
		(pad "2" smd custom
			(at 0 0.4445)
			(size 0.1397 0.1397)
			(layers "F.Cu" "F.Mask" "F.Paste")
			(net "P5V_C_EN_R")
			(options
				(clearance outline)
				(anchor circle)
			)
			(primitives
				(gr_poly
					(pts
						(arc
							(start -0.1778 -0.2794)
							(mid -0.249642 -0.249642)
							(end -0.2794 -0.1778)
						)
						(arc
							(start -0.2794 0.1778)
							(mid -0.249642 0.249642)
							(end -0.1778 0.2794)
						)
						(arc
							(start 0.1778 0.2794)
							(mid 0.249642 0.249642)
							(end 0.2794 0.1778)
						)
						(arc
							(start 0.2794 -0.1778)
							(mid 0.249642 -0.249642)
							(end 0.1778 -0.2794)
						)
					)
					(width 0)
					(fill yes)
				)
			)
		)
	)
	(footprint ""
		(layer "F.Cu")
		(at 210.861148 -11.162538 90)
		(property "Reference" "C40"
			(at 0 0 90)
			(layer "F.SilkS")
			(hide yes)
			(effects
				(font
					(size 1.27 1.27)
				)
			)
		)
		(property "Value" "SC10U16V5KX-7-GP-U"
			(at -0.0762 -6.1214 90)
			(unlocked yes)
			(layer "F.Fab")
			(hide yes)
			(effects
				(font
					(size 1.016 1.016)
					(thickness 0.1524)
				)
			)
		)
		(property "Device Type" "C805H58"
			(at -0.0762 -8.1534 90)
			(unlocked yes)
			(layer "F.Fab")
			(hide yes)
			(effects
				(font
					(size 1.016 1.016)
					(thickness 0.1524)
				)
			)
		)
		(duplicate_pad_numbers_are_jumpers no)
		(fp_line
			(start 0.635 0)
			(end -0.635 0)
			(stroke
				(width 0.508)
				(type default)
			)
			(layer "F.SilkS")
		)
		(fp_rect
			(start -0.9652 1.778)
			(end 0.9652 -1.778)
			(stroke
				(width 0)
				(type default)
			)
			(fill no)
			(layer "F.CrtYd")
		)
		(fp_poly
			(pts
				(xy -0.9652 -1.778) (xy 0.9652 -1.778) (xy 0.9652 1.778) (xy -0.9652 1.778)
			)
			(stroke
				(width 0)
				(type default)
			)
			(fill no)
			(layer "F.Fab")
		)
		(pad "1" smd rect
			(at 0 -0.9652 90)
			(size 1.397 1.143)
			(layers "F.Cu" "F.Mask" "F.Paste")
			(net "P5V_A_2")
		)
		(pad "2" smd rect
			(at 0 0.9652 90)
			(size 1.397 1.143)
			(layers "F.Cu" "F.Mask" "F.Paste")
			(net "GND")
		)
	)
	(footprint ""
		(layer "F.Cu")
		(at 430.387252 -275.735542 180)
		(property "Reference" "R354"
			(at 0 0 180)
			(layer "F.SilkS")
			(hide yes)
			(effects
				(font
					(size 1.27 1.27)
				)
			)
		)
		(property "Value" "0R2J-2-GP"
			(at 0.064008 -3.993896 180)
			(unlocked yes)
			(layer "F.Fab")
			(hide yes)
			(effects
				(font
					(size 1.016 1.016)
					(thickness 0.1524)
				)
			)
		)
		(property "Device Type" "R402H16"
			(at 0.064008 -5.517896 180)
			(unlocked yes)
			(layer "F.Fab")
			(hide yes)
			(effects
				(font
					(size 1.016 1.016)
					(thickness 0.1524)
				)
			)
		)
		(duplicate_pad_numbers_are_jumpers no)
		(fp_line
			(start 0.508 -0.9398)
			(end -0.508 -0.9398)
			(stroke
				(width 0.1524)
				(type default)
			)
			(layer "F.SilkS")
		)
		(fp_line
			(start -0.508 -0.9398)
			(end -0.508 0.9398)
			(stroke
				(width 0.1524)
				(type default)
			)
			(layer "F.SilkS")
		)
		(fp_rect
			(start -0.508 0.9398)
			(end 0.508 -0.9398)
			(stroke
				(width 0)
				(type default)
			)
			(fill no)
			(layer "F.CrtYd")
		)
		(fp_rect
			(start -0.508 0.9398)
			(end 0.508 -0.9398)
			(stroke
				(width 0)
				(type default)
			)
			(fill no)
			(layer "F.Fab")
		)
		(pad "1" smd custom
			(at 0 -0.4445 180)
			(size 0.1397 0.1397)
			(layers "F.Cu" "F.Mask" "F.Paste")
			(net "SW_HDD_G9")
			(options
				(clearance outline)
				(anchor circle)
			)
			(primitives
				(gr_poly
					(pts
						(arc
							(start -0.1778 -0.2794)
							(mid -0.249642 -0.249642)
							(end -0.2794 -0.1778)
						)
						(arc
							(start -0.2794 0.1778)
							(mid -0.249642 0.249642)
							(end -0.1778 0.2794)
						)
						(arc
							(start 0.1778 0.2794)
							(mid 0.249642 0.249642)
							(end 0.2794 0.1778)
						)
						(arc
							(start 0.2794 -0.1778)
							(mid 0.249642 -0.249642)
							(end 0.1778 -0.2794)
						)
					)
					(width 0)
					(fill yes)
				)
			)
		)
		(pad "2" smd custom
			(at 0 0.4445 180)
			(size 0.1397 0.1397)
			(layers "F.Cu" "F.Mask" "F.Paste")
			(net "SW_HDD_R9")
			(options
				(clearance outline)
				(anchor circle)
			)
			(primitives
				(gr_poly
					(pts
						(arc
							(start -0.1778 -0.2794)
							(mid -0.249642 -0.249642)
							(end -0.2794 -0.1778)
						)
						(arc
							(start -0.2794 0.1778)
							(mid -0.249642 0.249642)
							(end -0.1778 0.2794)
						)
						(arc
							(start 0.1778 0.2794)
							(mid 0.249642 0.249642)
							(end 0.2794 0.1778)
						)
						(arc
							(start 0.2794 -0.1778)
							(mid 0.249642 -0.249642)
							(end 0.1778 -0.2794)
						)
					)
					(width 0)
					(fill yes)
				)
			)
		)
	)
)
